(kicad_pcb
	(version 20260206)
	(generator "pcbnew")
	(generator_version "10.0")
	(general
		(thickness 1.6)
		(legacy_teardrops no)
	)
	(paper "A4")
	(title_block
		(title "03242023_DA0F0TMBIJ0_F0T_Motherboard_J_brd_V01_OCP.brd")
		(comment 1 "Grand Teton / footprints 2032-2038 of 6105")
	)
	(layers
		(0 "F.Cu" signal "TOP")
		(4 "In1.Cu" signal "GND")
		(6 "In2.Cu" signal "IN1")
		(8 "In3.Cu" signal "GND1")
		(10 "In4.Cu" signal "IN2")
		(12 "In5.Cu" signal "GND2")
		(14 "In6.Cu" signal "IN3")
		(16 "In7.Cu" signal "GND3")
		(18 "In8.Cu" signal "VCC")
		(20 "In9.Cu" signal "VCC1")
		(22 "In10.Cu" signal "GND4")
		(24 "In11.Cu" signal "IN4")
		(26 "In12.Cu" signal "GND5")
		(28 "In13.Cu" signal "IN5")
		(30 "In14.Cu" signal "GND6")
		(32 "In15.Cu" signal "IN6")
		(34 "In16.Cu" signal "GND7")
		(2 "B.Cu" signal "BOTTOM")
		(9 "F.Adhes" user "F.Adhesive")
		(11 "B.Adhes" user "B.Adhesive")
		(13 "F.Paste" user "Package Geometry/Pastemask Top")
		(15 "B.Paste" user "Package Geometry/Pastemask Bottom")
		(5 "F.SilkS" user "Ref Des/Silkscreen Top")
		(7 "B.SilkS" user "Ref Des/Silkscreen Bottom")
		(1 "F.Mask" user "Board Geometry/Soldermask Top")
		(3 "B.Mask" user "Board Geometry/Soldermask Bottom")
		(17 "Dwgs.User" user "User.Drawings")
		(19 "Cmts.User" user "User.Comments")
		(21 "Eco1.User" user "User.Eco1")
		(23 "Eco2.User" user "User.Eco2")
		(25 "Edge.Cuts" user "Board Geometry/Outline")
		(27 "Margin" user)
		(31 "F.CrtYd" user "Package Geometry/Place Bound Top")
		(29 "B.CrtYd" user "Package Geometry/Place Bound Bottom")
		(35 "F.Fab" user "Ref Des/Assembly Top")
		(33 "B.Fab" user "Ref Des/Assembly Bottom")
	)
	(footprint ""
		(layer "F.Cu")
		(at 114.68608 -119.846598 -90)
		(property "Reference" "R4036"
			(at 0 0 270)
			(layer "F.SilkS")
			(hide yes)
			(effects
				(font
					(size 1.27 1.27)
				)
			)
		)
		(property "Value" ""
			(at 0 0 270)
			(layer "F.Fab")
			(effects
				(font
					(size 1.27 1.27)
				)
			)
		)
		(duplicate_pad_numbers_are_jumpers no)
		(fp_line
			(start -0.7874 0.4064)
			(end -0.7874 -0.4064)
			(stroke
				(width 0.1524)
				(type default)
			)
			(layer "F.SilkS")
		)
		(fp_line
			(start 0.7874 0.4064)
			(end -0.7874 0.4064)
			(stroke
				(width 0.1524)
				(type default)
			)
			(layer "F.SilkS")
		)
		(fp_line
			(start -0.7874 -0.4064)
			(end 0.7874 -0.4064)
			(stroke
				(width 0.1524)
				(type default)
			)
			(layer "F.SilkS")
		)
		(fp_line
			(start 0.7874 -0.4064)
			(end 0.7874 0.4064)
			(stroke
				(width 0.1524)
				(type default)
			)
			(layer "F.SilkS")
		)
		(fp_line
			(start -0.67945 0.3048)
			(end -0.67945 -0.305054)
			(stroke
				(width 0.1)
				(type default)
			)
			(layer "F.Fab")
		)
		(fp_line
			(start -0.12065 0.3048)
			(end -0.67945 0.3048)
			(stroke
				(width 0.1)
				(type default)
			)
			(layer "F.Fab")
		)
		(fp_line
			(start 0.120396 0.3048)
			(end 0.120396 0.2794)
			(stroke
				(width 0.1)
				(type default)
			)
			(layer "F.Fab")
		)
		(fp_line
			(start 0.67945 0.3048)
			(end 0.120396 0.3048)
			(stroke
				(width 0.1)
				(type default)
			)
			(layer "F.Fab")
		)
		(fp_line
			(start -0.12065 0.2794)
			(end -0.12065 0.3048)
			(stroke
				(width 0.1)
				(type default)
			)
			(layer "F.Fab")
		)
		(fp_line
			(start 0.120396 0.2794)
			(end -0.12065 0.2794)
			(stroke
				(width 0.1)
				(type default)
			)
			(layer "F.Fab")
		)
		(fp_line
			(start -0.12065 -0.2794)
			(end 0.12065 -0.2794)
			(stroke
				(width 0.1)
				(type default)
			)
			(layer "F.Fab")
		)
		(fp_line
			(start 0.12065 -0.2794)
			(end 0.12065 -0.3048)
			(stroke
				(width 0.1)
				(type default)
			)
			(layer "F.Fab")
		)
		(fp_line
			(start 0.12065 -0.3048)
			(end 0.67945 -0.3048)
			(stroke
				(width 0.1)
				(type default)
			)
			(layer "F.Fab")
		)
		(fp_line
			(start 0.67945 -0.3048)
			(end 0.67945 0.3048)
			(stroke
				(width 0.1)
				(type default)
			)
			(layer "F.Fab")
		)
		(fp_line
			(start -0.67945 -0.305054)
			(end -0.12065 -0.305054)
			(stroke
				(width 0.1)
				(type default)
			)
			(layer "F.Fab")
		)
		(fp_line
			(start -0.12065 -0.305054)
			(end -0.12065 -0.2794)
			(stroke
				(width 0.1)
				(type default)
			)
			(layer "F.Fab")
		)
		(pad "1" smd circle
			(at -0.40005 0 270)
			(size 0 0)
			(layers "F.Cu" "F.Mask" "F.Paste")
			(net "P3V3_AUX")
		)
		(pad "2" smd circle
			(at 0.40005 0 270)
			(size 0 0)
			(layers "F.Cu" "F.Mask" "F.Paste")
			(net "P0V62_CPU0_RST_DDR_VREF")
		)
	)
	(footprint ""
		(layer "F.Cu")
		(at 434.443632 -107.17403 90)
		(property "Reference" "PC2086"
			(at 0 0 90)
			(layer "F.SilkS")
			(hide yes)
			(effects
				(font
					(size 1.27 1.27)
				)
			)
		)
		(property "Value" ""
			(at 0 0 90)
			(layer "F.Fab")
			(effects
				(font
					(size 1.27 1.27)
				)
			)
		)
		(duplicate_pad_numbers_are_jumpers no)
		(fp_line
			(start 0.7874 -0.4064)
			(end 0.7874 0.4064)
			(stroke
				(width 0.1524)
				(type default)
			)
			(layer "F.SilkS")
		)
		(fp_line
			(start -0.7874 -0.4064)
			(end 0.7874 -0.4064)
			(stroke
				(width 0.1524)
				(type default)
			)
			(layer "F.SilkS")
		)
		(fp_line
			(start 0.7874 0.4064)
			(end -0.7874 0.4064)
			(stroke
				(width 0.1524)
				(type default)
			)
			(layer "F.SilkS")
		)
		(fp_line
			(start -0.7874 0.4064)
			(end -0.7874 -0.4064)
			(stroke
				(width 0.1524)
				(type default)
			)
			(layer "F.SilkS")
		)
		(fp_line
			(start -0.12065 -0.305054)
			(end -0.12065 -0.2794)
			(stroke
				(width 0.1)
				(type default)
			)
			(layer "F.Fab")
		)
		(fp_line
			(start -0.67945 -0.305054)
			(end -0.12065 -0.305054)
			(stroke
				(width 0.1)
				(type default)
			)
			(layer "F.Fab")
		)
		(fp_line
			(start 0.67945 -0.3048)
			(end 0.67945 0.3048)
			(stroke
				(width 0.1)
				(type default)
			)
			(layer "F.Fab")
		)
		(fp_line
			(start 0.12065 -0.3048)
			(end 0.67945 -0.3048)
			(stroke
				(width 0.1)
				(type default)
			)
			(layer "F.Fab")
		)
		(fp_line
			(start 0.12065 -0.2794)
			(end 0.12065 -0.3048)
			(stroke
				(width 0.1)
				(type default)
			)
			(layer "F.Fab")
		)
		(fp_line
			(start -0.12065 -0.2794)
			(end 0.12065 -0.2794)
			(stroke
				(width 0.1)
				(type default)
			)
			(layer "F.Fab")
		)
		(fp_line
			(start 0.120396 0.2794)
			(end -0.12065 0.2794)
			(stroke
				(width 0.1)
				(type default)
			)
			(layer "F.Fab")
		)
		(fp_line
			(start -0.12065 0.2794)
			(end -0.12065 0.3048)
			(stroke
				(width 0.1)
				(type default)
			)
			(layer "F.Fab")
		)
		(fp_line
			(start 0.67945 0.3048)
			(end 0.120396 0.3048)
			(stroke
				(width 0.1)
				(type default)
			)
			(layer "F.Fab")
		)
		(fp_line
			(start 0.120396 0.3048)
			(end 0.120396 0.2794)
			(stroke
				(width 0.1)
				(type default)
			)
			(layer "F.Fab")
		)
		(fp_line
			(start -0.12065 0.3048)
			(end -0.67945 0.3048)
			(stroke
				(width 0.1)
				(type default)
			)
			(layer "F.Fab")
		)
		(fp_line
			(start -0.67945 0.3048)
			(end -0.67945 -0.305054)
			(stroke
				(width 0.1)
				(type default)
			)
			(layer "F.Fab")
		)
		(pad "1" smd circle
			(at -0.40005 0 90)
			(size 0 0)
			(layers "F.Cu" "F.Mask" "F.Paste")
			(net "P3V3_OCP_VCC_1")
		)
		(pad "2" smd circle
			(at 0.40005 0 90)
			(size 0 0)
			(layers "F.Cu" "F.Mask" "F.Paste")
			(net "GND")
		)
	)
	(footprint ""
		(layer "F.Cu")
		(at 164.52088 -46.954948 180)
		(property "Reference" "R1605"
			(at 0 0 180)
			(layer "F.SilkS")
			(hide yes)
			(effects
				(font
					(size 1.27 1.27)
				)
			)
		)
		(property "Value" ""
			(at 0 0 180)
			(layer "F.Fab")
			(effects
				(font
					(size 1.27 1.27)
				)
			)
		)
		(duplicate_pad_numbers_are_jumpers no)
		(fp_line
			(start 0.7874 0.4064)
			(end -0.7874 0.4064)
			(stroke
				(width 0.1524)
				(type default)
			)
			(layer "F.SilkS")
		)
		(fp_line
			(start 0.7874 -0.4064)
			(end 0.7874 0.4064)
			(stroke
				(width 0.1524)
				(type default)
			)
			(layer "F.SilkS")
		)
		(fp_line
			(start -0.7874 0.4064)
			(end -0.7874 -0.4064)
			(stroke
				(width 0.1524)
				(type default)
			)
			(layer "F.SilkS")
		)
		(fp_line
			(start -0.7874 -0.4064)
			(end 0.7874 -0.4064)
			(stroke
				(width 0.1524)
				(type default)
			)
			(layer "F.SilkS")
		)
		(fp_line
			(start 0.67945 0.3048)
			(end 0.120396 0.3048)
			(stroke
				(width 0.1)
				(type default)
			)
			(layer "F.Fab")
		)
		(fp_line
			(start 0.67945 -0.3048)
			(end 0.67945 0.3048)
			(stroke
				(width 0.1)
				(type default)
			)
			(layer "F.Fab")
		)
		(fp_line
			(start 0.12065 -0.2794)
			(end 0.12065 -0.3048)
			(stroke
				(width 0.1)
				(type default)
			)
			(layer "F.Fab")
		)
		(fp_line
			(start 0.12065 -0.3048)
			(end 0.67945 -0.3048)
			(stroke
				(width 0.1)
				(type default)
			)
			(layer "F.Fab")
		)
		(fp_line
			(start 0.120396 0.3048)
			(end 0.120396 0.2794)
			(stroke
				(width 0.1)
				(type default)
			)
			(layer "F.Fab")
		)
		(fp_line
			(start 0.120396 0.2794)
			(end -0.12065 0.2794)
			(stroke
				(width 0.1)
				(type default)
			)
			(layer "F.Fab")
		)
		(fp_line
			(start -0.12065 0.3048)
			(end -0.67945 0.3048)
			(stroke
				(width 0.1)
				(type default)
			)
			(layer "F.Fab")
		)
		(fp_line
			(start -0.12065 0.2794)
			(end -0.12065 0.3048)
			(stroke
				(width 0.1)
				(type default)
			)
			(layer "F.Fab")
		)
		(fp_line
			(start -0.12065 -0.2794)
			(end 0.12065 -0.2794)
			(stroke
				(width 0.1)
				(type default)
			)
			(layer "F.Fab")
		)
		(fp_line
			(start -0.12065 -0.305054)
			(end -0.12065 -0.2794)
			(stroke
				(width 0.1)
				(type default)
			)
			(layer "F.Fab")
		)
		(fp_line
			(start -0.67945 0.3048)
			(end -0.67945 -0.305054)
			(stroke
				(width 0.1)
				(type default)
			)
			(layer "F.Fab")
		)
		(fp_line
			(start -0.67945 -0.305054)
			(end -0.12065 -0.305054)
			(stroke
				(width 0.1)
				(type default)
			)
			(layer "F.Fab")
		)
		(pad "1" smd circle
			(at -0.40005 0 180)
			(size 0 0)
			(layers "F.Cu" "F.Mask" "F.Paste")
			(net "PD_M2_0_DEVSLP")
		)
		(pad "2" smd circle
			(at 0.40005 0 180)
			(size 0 0)
			(layers "F.Cu" "F.Mask" "F.Paste")
			(net "GND")
		)
	)
	(footprint ""
		(layer "F.Cu")
		(at 358.84104 -315.66739 90)
		(property "Reference" "PC319"
			(at 0 0 90)
			(layer "F.SilkS")
			(hide yes)
			(effects
				(font
					(size 1.27 1.27)
				)
			)
		)
		(property "Value" ""
			(at 0 0 90)
			(layer "F.Fab")
			(effects
				(font
					(size 1.27 1.27)
				)
			)
		)
		(duplicate_pad_numbers_are_jumpers no)
		(fp_line
			(start 2.750058 0.999998)
			(end -2.750058 0.999998)
			(stroke
				(width 0.1524)
				(type default)
			)
			(layer "F.SilkS")
		)
		(fp_circle
			(center 0 0.999998)
			(end 0 3.750056)
			(stroke
				(width 0.1524)
				(type default)
			)
			(fill no)
			(layer "F.SilkS")
		)
		(fp_poly
			(pts
				(arc
					(start 2.750058 0.999998)
					(mid 0 3.750056)
					(end -2.750058 0.999998)
				)
			)
			(stroke
				(width 0)
				(type default)
			)
			(fill yes)
			(layer "F.SilkS")
		)
		(fp_circle
			(center 0 0.999998)
			(end 0 3.750056)
			(stroke
				(width 0.1)
				(type default)
			)
			(fill no)
			(layer "F.Fab")
		)
		(pad "1" thru_hole rect
			(at 0 0 90)
			(size 1.5748 1.5748)
			(drill 1.0668)
			(layers "*.Cu" "*.Mask")
			(remove_unused_layers no)
			(net "PVCCIN_CPU0")
			(clearance 0)
			(padstack
				(mode front_inner_back)
				(layer "Inner"
					(shape circle)
					(size 1.5748 1.5748)
					(clearance 0)
				)
				(layer "B.Cu"
					(shape rect)
					(size 1.5748 1.5748)
					(clearance 0)
				)
			)
		)
		(pad "2" thru_hole circle
			(at 0 1.999996 90)
			(size 1.5748 1.5748)
			(drill 1.0668)
			(layers "*.Cu" "*.Mask")
			(remove_unused_layers no)
			(net "GND")
			(clearance 0)
		)
	)
	(footprint ""
		(layer "F.Cu")
		(at 105.3084 -249.320558 -90)
		(property "Reference" "C236"
			(at 0 0 270)
			(layer "F.SilkS")
			(hide yes)
			(effects
				(font
					(size 1.27 1.27)
				)
			)
		)
		(property "Value" ""
			(at 0 0 270)
			(layer "F.Fab")
			(effects
				(font
					(size 1.27 1.27)
				)
			)
		)
		(duplicate_pad_numbers_are_jumpers no)
		(fp_line
			(start -0.7874 0.4064)
			(end -0.7874 -0.4064)
			(stroke
				(width 0.1524)
				(type default)
			)
			(layer "F.SilkS")
		)
		(fp_line
			(start 0.7874 0.4064)
			(end -0.7874 0.4064)
			(stroke
				(width 0.1524)
				(type default)
			)
			(layer "F.SilkS")
		)
		(fp_line
			(start -0.7874 -0.4064)
			(end 0.7874 -0.4064)
			(stroke
				(width 0.1524)
				(type default)
			)
			(layer "F.SilkS")
		)
		(fp_line
			(start 0.7874 -0.4064)
			(end 0.7874 0.4064)
			(stroke
				(width 0.1524)
				(type default)
			)
			(layer "F.SilkS")
		)
		(fp_line
			(start -0.67945 0.3048)
			(end -0.67945 -0.305054)
			(stroke
				(width 0.1)
				(type default)
			)
			(layer "F.Fab")
		)
		(fp_line
			(start -0.12065 0.3048)
			(end -0.67945 0.3048)
			(stroke
				(width 0.1)
				(type default)
			)
			(layer "F.Fab")
		)
		(fp_line
			(start 0.120396 0.3048)
			(end 0.120396 0.2794)
			(stroke
				(width 0.1)
				(type default)
			)
			(layer "F.Fab")
		)
		(fp_line
			(start 0.67945 0.3048)
			(end 0.120396 0.3048)
			(stroke
				(width 0.1)
				(type default)
			)
			(layer "F.Fab")
		)
		(fp_line
			(start -0.12065 0.2794)
			(end -0.12065 0.3048)
			(stroke
				(width 0.1)
				(type default)
			)
			(layer "F.Fab")
		)
		(fp_line
			(start 0.120396 0.2794)
			(end -0.12065 0.2794)
			(stroke
				(width 0.1)
				(type default)
			)
			(layer "F.Fab")
		)
		(fp_line
			(start -0.12065 -0.2794)
			(end 0.12065 -0.2794)
			(stroke
				(width 0.1)
				(type default)
			)
			(layer "F.Fab")
		)
		(fp_line
			(start 0.12065 -0.2794)
			(end 0.12065 -0.3048)
			(stroke
				(width 0.1)
				(type default)
			)
			(layer "F.Fab")
		)
		(fp_line
			(start 0.12065 -0.3048)
			(end 0.67945 -0.3048)
			(stroke
				(width 0.1)
				(type default)
			)
			(layer "F.Fab")
		)
		(fp_line
			(start 0.67945 -0.3048)
			(end 0.67945 0.3048)
			(stroke
				(width 0.1)
				(type default)
			)
			(layer "F.Fab")
		)
		(fp_line
			(start -0.67945 -0.305054)
			(end -0.12065 -0.305054)
			(stroke
				(width 0.1)
				(type default)
			)
			(layer "F.Fab")
		)
		(fp_line
			(start -0.12065 -0.305054)
			(end -0.12065 -0.2794)
			(stroke
				(width 0.1)
				(type default)
			)
			(layer "F.Fab")
		)
		(pad "1" smd circle
			(at -0.40005 0 270)
			(size 0 0)
			(layers "F.Cu" "F.Mask" "F.Paste")
			(net "PVCCIN_CPU1")
		)
		(pad "2" smd circle
			(at 0.40005 0 270)
			(size 0 0)
			(layers "F.Cu" "F.Mask" "F.Paste")
			(net "GND")
		)
	)
	(footprint ""
		(layer "F.Cu")
		(at 321.531488 -408.517344 -90)
		(property "Reference" "C913"
			(at 0 0 270)
			(layer "F.SilkS")
			(hide yes)
			(effects
				(font
					(size 1.27 1.27)
				)
			)
		)
		(property "Value" ""
			(at 0 0 270)
			(layer "F.Fab")
			(effects
				(font
					(size 1.27 1.27)
				)
			)
		)
		(duplicate_pad_numbers_are_jumpers no)
		(fp_line
			(start -0.299974 0.150114)
			(end -0.299974 -0.150114)
			(stroke
				(width 0.1)
				(type default)
			)
			(layer "F.Fab")
		)
		(fp_line
			(start 0.299974 0.150114)
			(end -0.299974 0.150114)
			(stroke
				(width 0.1)
				(type default)
			)
			(layer "F.Fab")
		)
		(fp_line
			(start -0.299974 -0.150114)
			(end 0.299974 -0.150114)
			(stroke
				(width 0.1)
				(type default)
			)
			(layer "F.Fab")
		)
		(fp_line
			(start 0.299974 -0.150114)
			(end 0.299974 0.150114)
			(stroke
				(width 0.1)
				(type default)
			)
			(layer "F.Fab")
		)
		(pad "1" smd rect
			(at -0.2667 0 270)
			(size 0.3048 0.381)
			(layers "F.Cu" "F.Mask" "F.Paste")
			(net "P5E_CPU0_PE0_TX_C_DP<10>")
		)
		(pad "2" smd rect
			(at 0.2667 0 270)
			(size 0.3048 0.381)
			(layers "F.Cu" "F.Mask" "F.Paste")
			(net "P5E_CPU0_PE0_TX_DP<10>")
		)
	)
	(footprint ""
		(layer "F.Cu")
		(at 128.70688 -92.674948 -90)
		(property "Reference" "R4401"
			(at 0 0 270)
			(layer "F.SilkS")
			(hide yes)
			(effects
				(font
					(size 1.27 1.27)
				)
			)
		)
		(property "Value" ""
			(at 0 0 270)
			(layer "F.Fab")
			(effects
				(font
					(size 1.27 1.27)
				)
			)
		)
		(duplicate_pad_numbers_are_jumpers no)
		(fp_line
			(start -0.7874 0.4064)
			(end -0.7874 -0.4064)
			(stroke
				(width 0.1524)
				(type default)
			)
			(layer "F.SilkS")
		)
		(fp_line
			(start 0.7874 0.4064)
			(end -0.7874 0.4064)
			(stroke
				(width 0.1524)
				(type default)
			)
			(layer "F.SilkS")
		)
		(fp_line
			(start -0.7874 -0.4064)
			(end 0.7874 -0.4064)
			(stroke
				(width 0.1524)
				(type default)
			)
			(layer "F.SilkS")
		)
		(fp_line
			(start 0.7874 -0.4064)
			(end 0.7874 0.4064)
			(stroke
				(width 0.1524)
				(type default)
			)
			(layer "F.SilkS")
		)
		(fp_line
			(start -0.67945 0.3048)
			(end -0.67945 -0.305054)
			(stroke
				(width 0.1)
				(type default)
			)
			(layer "F.Fab")
		)
		(fp_line
			(start -0.12065 0.3048)
			(end -0.67945 0.3048)
			(stroke
				(width 0.1)
				(type default)
			)
			(layer "F.Fab")
		)
		(fp_line
			(start 0.120396 0.3048)
			(end 0.120396 0.2794)
			(stroke
				(width 0.1)
				(type default)
			)
			(layer "F.Fab")
		)
		(fp_line
			(start 0.67945 0.3048)
			(end 0.120396 0.3048)
			(stroke
				(width 0.1)
				(type default)
			)
			(layer "F.Fab")
		)
		(fp_line
			(start -0.12065 0.2794)
			(end -0.12065 0.3048)
			(stroke
				(width 0.1)
				(type default)
			)
			(layer "F.Fab")
		)
		(fp_line
			(start 0.120396 0.2794)
			(end -0.12065 0.2794)
			(stroke
				(width 0.1)
				(type default)
			)
			(layer "F.Fab")
		)
		(fp_line
			(start -0.12065 -0.2794)
			(end 0.12065 -0.2794)
			(stroke
				(width 0.1)
				(type default)
			)
			(layer "F.Fab")
		)
		(fp_line
			(start 0.12065 -0.2794)
			(end 0.12065 -0.3048)
			(stroke
				(width 0.1)
				(type default)
			)
			(layer "F.Fab")
		)
		(fp_line
			(start 0.12065 -0.3048)
			(end 0.67945 -0.3048)
			(stroke
				(width 0.1)
				(type default)
			)
			(layer "F.Fab")
		)
		(fp_line
			(start 0.67945 -0.3048)
			(end 0.67945 0.3048)
			(stroke
				(width 0.1)
				(type default)
			)
			(layer "F.Fab")
		)
		(fp_line
			(start -0.67945 -0.305054)
			(end -0.12065 -0.305054)
			(stroke
				(width 0.1)
				(type default)
			)
			(layer "F.Fab")
		)
		(fp_line
			(start -0.12065 -0.305054)
			(end -0.12065 -0.2794)
			(stroke
				(width 0.1)
				(type default)
			)
			(layer "F.Fab")
		)
		(pad "1" smd circle
			(at -0.40005 0 270)
			(size 0 0)
			(layers "F.Cu" "F.Mask" "F.Paste")
			(net "PVNN_TERM_CPU0")
		)
		(pad "2" smd circle
			(at 0.40005 0 270)
			(size 0 0)
			(layers "F.Cu" "F.Mask" "F.Paste")
			(net "H_CPU0_MEMHOT_OUT_LVC1_R_N")
		)
	)
)
